# T6G (Grand Teton) — schematic netlist excerpt (pin names and nets, part order shuffled) for the footprints in the layout excerpt that follows; sources: Cadence DE-HDL packaged netlist, KiCad conversion of 04192023_DAF0TMB3IC0_F0TG_MB_C_brd_V02_OCP.brd

PR6602  Q_RES  49.9 1% CHIP  pkg 0402LF  page 364 : A = P0V9_RETIMER_CPU1_SENSE_SH_N ; B = GND
C1578  Q_CAP_DIFFBUS  DIFF BUS_0.22UF 6.3V 20% X6S  pkg C0201  page 65 : \1\ = P5E_CPU0_G3_TX_C_DN<0> ; \2\ = P5E_CPU0_G3_TX_DN<0>
C849  Q_CAP_DIFFBUS  DIFF BUS_0.22UF 6.3V 20% X6S  pkg C0201  page 64 : \1\ = P5E_CPU0_P2_TX_C_DP<10> ; \2\ = P5E_CPU0_P2_TX_DP<10>

(kicad_pcb
	(version 20260206)
	(generator "pcbnew")
	(generator_version "10.0")
	(general
		(thickness 1.6)
		(legacy_teardrops no)
	)
	(paper "A4")
	(title_block
		(title "04192023_DAF0TMB3IC0_F0TG_MB_C_brd_V02_OCP.brd")
		(comment 1 "Grand Teton / footprints 2392-2394 of 8354")
	)
	(layers
		(0 "F.Cu" signal "TOP")
		(4 "In1.Cu" signal "GND")
		(6 "In2.Cu" signal "IN1")
		(8 "In3.Cu" signal "GND1")
		(10 "In4.Cu" signal "IN2")
		(12 "In5.Cu" signal "GND2")
		(14 "In6.Cu" signal "IN3")
		(16 "In7.Cu" signal "GND3")
		(18 "In8.Cu" signal "VCC")
		(20 "In9.Cu" signal "VCC1")
		(22 "In10.Cu" signal "GND4")
		(24 "In11.Cu" signal "IN4")
		(26 "In12.Cu" signal "GND5")
		(28 "In13.Cu" signal "IN5")
		(30 "In14.Cu" signal "GND6")
		(32 "In15.Cu" signal "IN6")
		(34 "In16.Cu" signal "GND7")
		(2 "B.Cu" signal "BOTTOM")
		(9 "F.Adhes" user "F.Adhesive")
		(11 "B.Adhes" user "B.Adhesive")
		(13 "F.Paste" user "Package Geometry/Pastemask Top")
		(15 "B.Paste" user "Package Geometry/Pastemask Bottom")
		(5 "F.SilkS" user "Ref Des/Silkscreen Top")
		(7 "B.SilkS" user "Ref Des/Silkscreen Bottom")
		(1 "F.Mask" user "Board Geometry/Soldermask Top")
		(3 "B.Mask" user "Board Geometry/Soldermask Bottom")
		(17 "Dwgs.User" user "User.Drawings")
		(19 "Cmts.User" user "User.Comments")
		(21 "Eco1.User" user "User.Eco1")
		(23 "Eco2.User" user "User.Eco2")
		(25 "Edge.Cuts" user "Board Geometry/Outline")
		(27 "Margin" user)
		(31 "F.CrtYd" user "Package Geometry/Place Bound Top")
		(29 "B.CrtYd" user "Package Geometry/Place Bound Bottom")
		(35 "F.Fab" user "Ref Des/Assembly Top")
		(33 "B.Fab" user "Ref Des/Assembly Bottom")
	)
	(footprint ""
		(layer "F.Cu")
		(at 432.2572 -17.624298 90)
		(property "Reference" "C1578"
			(at 0 0 90)
			(layer "F.SilkS")
			(hide yes)
			(effects
				(font
					(size 1.27 1.27)
				)
			)
		)
		(property "Value" ""
			(at 0 0 90)
			(layer "F.Fab")
			(effects
				(font
					(size 1.27 1.27)
				)
			)
		)
		(duplicate_pad_numbers_are_jumpers no)
		(fp_line
			(start 0.299974 -0.150114)
			(end 0.299974 0.150114)
			(stroke
				(width 0.1)
				(type default)
			)
			(layer "F.Fab")
		)
		(fp_line
			(start -0.299974 -0.150114)
			(end 0.299974 -0.150114)
			(stroke
				(width 0.1)
				(type default)
			)
			(layer "F.Fab")
		)
		(fp_line
			(start 0.299974 0.150114)
			(end -0.299974 0.150114)
			(stroke
				(width 0.1)
				(type default)
			)
			(layer "F.Fab")
		)
		(fp_line
			(start -0.299974 0.150114)
			(end -0.299974 -0.150114)
			(stroke
				(width 0.1)
				(type default)
			)
			(layer "F.Fab")
		)
		(pad "1" smd rect
			(at -0.2667 0 90)
			(size 0.3048 0.381)
			(layers "F.Cu" "F.Mask" "F.Paste")
			(net "P5E_CPU0_G3_TX_C_DN<0>")
		)
		(pad "2" smd rect
			(at 0.2667 0 90)
			(size 0.3048 0.381)
			(layers "F.Cu" "F.Mask" "F.Paste")
			(net "P5E_CPU0_G3_TX_DN<0>")
		)
	)
	(footprint ""
		(layer "F.Cu")
		(at 417.33724 -383.88163 -90)
		(property "Reference" "C849"
			(at 0 0 270)
			(layer "F.SilkS")
			(hide yes)
			(effects
				(font
					(size 1.27 1.27)
				)
			)
		)
		(property "Value" ""
			(at 0 0 270)
			(layer "F.Fab")
			(effects
				(font
					(size 1.27 1.27)
				)
			)
		)
		(duplicate_pad_numbers_are_jumpers no)
		(fp_line
			(start -0.299974 0.150114)
			(end -0.299974 -0.150114)
			(stroke
				(width 0.1)
				(type default)
			)
			(layer "F.Fab")
		)
		(fp_line
			(start 0.299974 0.150114)
			(end -0.299974 0.150114)
			(stroke
				(width 0.1)
				(type default)
			)
			(layer "F.Fab")
		)
		(fp_line
			(start -0.299974 -0.150114)
			(end 0.299974 -0.150114)
			(stroke
				(width 0.1)
				(type default)
			)
			(layer "F.Fab")
		)
		(fp_line
			(start 0.299974 -0.150114)
			(end 0.299974 0.150114)
			(stroke
				(width 0.1)
				(type default)
			)
			(layer "F.Fab")
		)
		(pad "1" smd rect
			(at -0.2667 0 270)
			(size 0.3048 0.381)
			(layers "F.Cu" "F.Mask" "F.Paste")
			(net "P5E_CPU0_P2_TX_C_DP<10>")
		)
		(pad "2" smd rect
			(at 0.2667 0 270)
			(size 0.3048 0.381)
			(layers "F.Cu" "F.Mask" "F.Paste")
			(net "P5E_CPU0_P2_TX_DP<10>")
		)
	)
	(footprint ""
		(layer "F.Cu")
		(at 8.406384 -381.562356)
		(property "Reference" "PR6602"
			(at 0 0 0)
			(layer "F.SilkS")
			(hide yes)
			(effects
				(font
					(size 1.27 1.27)
				)
			)
		)
		(property "Value" ""
			(at 0 0 0)
			(layer "F.Fab")
			(effects
				(font
					(size 1.27 1.27)
				)
			)
		)
		(duplicate_pad_numbers_are_jumpers no)
		(fp_line
			(start -0.7874 -0.4064)
			(end 0.7874 -0.4064)
			(stroke
				(width 0.1524)
				(type default)
			)
			(layer "F.SilkS")
		)
		(fp_line
			(start -0.7874 0.4064)
			(end -0.7874 -0.4064)
			(stroke
				(width 0.1524)
				(type default)
			)
			(layer "F.SilkS")
		)
		(fp_line
			(start 0.7874 -0.4064)
			(end 0.7874 0.4064)
			(stroke
				(width 0.1524)
				(type default)
			)
			(layer "F.SilkS")
		)
		(fp_line
			(start 0.7874 0.4064)
			(end -0.7874 0.4064)
			(stroke
				(width 0.1524)
				(type default)
			)
			(layer "F.SilkS")
		)
		(fp_line
			(start -0.67945 -0.305054)
			(end -0.12065 -0.305054)
			(stroke
				(width 0.1)
				(type default)
			)
			(layer "F.Fab")
		)
		(fp_line
			(start -0.67945 0.3048)
			(end -0.67945 -0.305054)
			(stroke
				(width 0.1)
				(type default)
			)
			(layer "F.Fab")
		)
		(fp_line
			(start -0.12065 -0.305054)
			(end -0.12065 -0.2794)
			(stroke
				(width 0.1)
				(type default)
			)
			(layer "F.Fab")
		)
		(fp_line
			(start -0.12065 -0.2794)
			(end 0.12065 -0.2794)
			(stroke
				(width 0.1)
				(type default)
			)
			(layer "F.Fab")
		)
		(fp_line
			(start -0.12065 0.2794)
			(end -0.12065 0.3048)
			(stroke
				(width 0.1)
				(type default)
			)
			(layer "F.Fab")
		)
		(fp_line
			(start -0.12065 0.3048)
			(end -0.67945 0.3048)
			(stroke
				(width 0.1)
				(type default)
			)
			(layer "F.Fab")
		)
		(fp_line
			(start 0.120396 0.2794)
			(end -0.12065 0.2794)
			(stroke
				(width 0.1)
				(type default)
			)
			(layer "F.Fab")
		)
		(fp_line
			(start 0.120396 0.3048)
			(end 0.120396 0.2794)
			(stroke
				(width 0.1)
				(type default)
			)
			(layer "F.Fab")
		)
		(fp_line
			(start 0.12065 -0.3048)
			(end 0.67945 -0.3048)
			(stroke
				(width 0.1)
				(type default)
			)
			(layer "F.Fab")
		)
		(fp_line
			(start 0.12065 -0.2794)
			(end 0.12065 -0.3048)
			(stroke
				(width 0.1)
				(type default)
			)
			(layer "F.Fab")
		)
		(fp_line
			(start 0.67945 -0.3048)
			(end 0.67945 0.3048)
			(stroke
				(width 0.1)
				(type default)
			)
			(layer "F.Fab")
		)
		(fp_line
			(start 0.67945 0.3048)
			(end 0.120396 0.3048)
			(stroke
				(width 0.1)
				(type default)
			)
			(layer "F.Fab")
		)
		(pad "1" smd circle
			(at -0.40005 0)
			(size 0 0)
			(layers "F.Cu" "F.Mask" "F.Paste")
			(net "P0V9_RETIMER_CPU1_SENSE_SH_N")
		)
		(pad "2" smd circle
			(at 0.40005 0)
			(size 0 0)
			(layers "F.Cu" "F.Mask" "F.Paste")
			(net "GND")
		)
	)
)
